(kicad_pcb
	(version 20260206)
	(generator "pcbnew")
	(generator_version "10.0")
	(general
		(thickness 1.6)
		(legacy_teardrops no)
	)
	(paper "A4")
	(title_block
		(title "Bryce Canyon_R.DPB_16317-1_OCP.brd")
		(comment 1 "Bryce Canyon / footprints 1860-1866 of 2099")
	)
	(layers
		(0 "F.Cu" signal "TOP")
		(4 "In1.Cu" signal "L2GND")
		(6 "In2.Cu" signal "L3")
		(8 "In3.Cu" signal "L4VCC")
		(10 "In4.Cu" signal "L5VCC")
		(12 "In5.Cu" signal "L6")
		(14 "In6.Cu" signal "L7GND")
		(2 "B.Cu" signal "BOTTOM")
		(9 "F.Adhes" user "F.Adhesive")
		(11 "B.Adhes" user "B.Adhesive")
		(13 "F.Paste" user "Package Geometry/Pastemask Top")
		(15 "B.Paste" user "Package Geometry/Pastemask Bottom")
		(5 "F.SilkS" user "Ref Des/Silkscreen Top")
		(7 "B.SilkS" user "Ref Des/Silkscreen Bottom")
		(1 "F.Mask" user "Board Geometry/Soldermask Top")
		(3 "B.Mask" user "Board Geometry/Soldermask Bottom")
		(17 "Dwgs.User" user "User.Drawings")
		(19 "Cmts.User" user "User.Comments")
		(21 "Eco1.User" user "User.Eco1")
		(23 "Eco2.User" user "User.Eco2")
		(25 "Edge.Cuts" user "Board Geometry/Outline")
		(27 "Margin" user)
		(31 "F.CrtYd" user "Package Geometry/Place Bound Top")
		(29 "B.CrtYd" user "Package Geometry/Place Bound Bottom")
		(35 "F.Fab" user "Ref Des/Assembly Top")
		(33 "B.Fab" user "Ref Des/Assembly Bottom")
	)
	(footprint ""
		(layer "F.Cu")
		(at 245.578122 -367.131346 90)
		(property "Reference" "R1111"
			(at 0 0 90)
			(layer "F.SilkS")
			(hide yes)
			(effects
				(font
					(size 1.27 1.27)
				)
			)
		)
		(property "Value" "10R2F-L-GP"
			(at 0.064008 -3.993896 90)
			(unlocked yes)
			(layer "F.Fab")
			(hide yes)
			(effects
				(font
					(size 1.016 1.016)
					(thickness 0.1524)
				)
			)
		)
		(property "Device Type" "R402H14"
			(at 0.064008 -5.517896 90)
			(unlocked yes)
			(layer "F.Fab")
			(hide yes)
			(effects
				(font
					(size 1.016 1.016)
					(thickness 0.1524)
				)
			)
		)
		(duplicate_pad_numbers_are_jumpers no)
		(fp_line
			(start 0.508 -0.9398)
			(end -0.508 -0.9398)
			(stroke
				(width 0.1524)
				(type default)
			)
			(layer "F.SilkS")
		)
		(fp_line
			(start -0.508 -0.9398)
			(end -0.508 0.9398)
			(stroke
				(width 0.1524)
				(type default)
			)
			(layer "F.SilkS")
		)
		(fp_rect
			(start -0.508 0.9398)
			(end 0.508 -0.9398)
			(stroke
				(width 0)
				(type default)
			)
			(fill no)
			(layer "F.CrtYd")
		)
		(fp_rect
			(start -0.508 0.9398)
			(end 0.508 -0.9398)
			(stroke
				(width 0)
				(type default)
			)
			(fill no)
			(layer "F.Fab")
		)
		(pad "1" smd custom
			(at 0 -0.4445 90)
			(size 0.1397 0.1397)
			(layers "F.Cu" "F.Mask" "F.Paste")
			(net "MB3_CM_SENSE_R1_N")
			(options
				(clearance outline)
				(anchor circle)
			)
			(primitives
				(gr_poly
					(pts
						(arc
							(start -0.1778 -0.2794)
							(mid -0.249642 -0.249642)
							(end -0.2794 -0.1778)
						)
						(arc
							(start -0.2794 0.1778)
							(mid -0.249642 0.249642)
							(end -0.1778 0.2794)
						)
						(arc
							(start 0.1778 0.2794)
							(mid 0.249642 0.249642)
							(end 0.2794 0.1778)
						)
						(arc
							(start 0.2794 -0.1778)
							(mid 0.249642 -0.249642)
							(end 0.1778 -0.2794)
						)
					)
					(width 0)
					(fill yes)
				)
			)
		)
		(pad "2" smd custom
			(at 0 0.4445 90)
			(size 0.1397 0.1397)
			(layers "F.Cu" "F.Mask" "F.Paste")
			(net "MB3_HS_SENSE_N")
			(options
				(clearance outline)
				(anchor circle)
			)
			(primitives
				(gr_poly
					(pts
						(arc
							(start -0.1778 -0.2794)
							(mid -0.249642 -0.249642)
							(end -0.2794 -0.1778)
						)
						(arc
							(start -0.2794 0.1778)
							(mid -0.249642 0.249642)
							(end -0.1778 0.2794)
						)
						(arc
							(start 0.1778 0.2794)
							(mid 0.249642 0.249642)
							(end 0.2794 0.1778)
						)
						(arc
							(start 0.2794 -0.1778)
							(mid 0.249642 -0.249642)
							(end 0.1778 -0.2794)
						)
					)
					(width 0)
					(fill yes)
				)
			)
		)
	)
	(footprint ""
		(layer "F.Cu")
		(at 475.107 -31.877 -90)
		(property "Reference" "C486"
			(at 0 0 270)
			(layer "F.SilkS")
			(hide yes)
			(effects
				(font
					(size 1.27 1.27)
				)
			)
		)
		(property "Value" "SC10U16V6KX-2GP"
			(at -0.0762 -5.1308 270)
			(unlocked yes)
			(layer "F.Fab")
			(hide yes)
			(effects
				(font
					(size 1.016 1.016)
					(thickness 0.1524)
				)
			)
		)
		(property "Device Type" "C1206H71"
			(at -0.127 -6.6548 270)
			(unlocked yes)
			(layer "F.Fab")
			(hide yes)
			(effects
				(font
					(size 1.016 1.016)
					(thickness 0.1524)
				)
			)
		)
		(duplicate_pad_numbers_are_jumpers no)
		(fp_line
			(start -1.016 2.2352)
			(end -1.016 0.8382)
			(stroke
				(width 0.1524)
				(type default)
			)
			(layer "F.SilkS")
		)
		(fp_line
			(start 1.016 2.2352)
			(end -1.016 2.2352)
			(stroke
				(width 0.1524)
				(type default)
			)
			(layer "F.SilkS")
		)
		(fp_line
			(start 1.016 0.8382)
			(end 1.016 2.2352)
			(stroke
				(width 0.1524)
				(type default)
			)
			(layer "F.SilkS")
		)
		(fp_line
			(start -1.016 -0.8382)
			(end -1.016 -2.2352)
			(stroke
				(width 0.1524)
				(type default)
			)
			(layer "F.SilkS")
		)
		(fp_line
			(start -1.016 -2.2352)
			(end 1.016 -2.2352)
			(stroke
				(width 0.1524)
				(type default)
			)
			(layer "F.SilkS")
		)
		(fp_line
			(start 1.016 -2.2352)
			(end 1.016 -0.8382)
			(stroke
				(width 0.1524)
				(type default)
			)
			(layer "F.SilkS")
		)
		(fp_rect
			(start -1.0922 2.3114)
			(end 1.0922 -2.3114)
			(stroke
				(width 0)
				(type default)
			)
			(fill no)
			(layer "F.CrtYd")
		)
		(fp_poly
			(pts
				(xy 1.0922 -2.3114) (xy 1.0922 2.3114) (xy -1.0922 2.3114) (xy -1.0922 -2.3114)
			)
			(stroke
				(width 0)
				(type default)
			)
			(fill no)
			(layer "F.Fab")
		)
		(pad "1" smd rect
			(at 0 -1.397 270)
			(size 1.651 1.27)
			(layers "F.Cu" "F.Mask" "F.Paste")
			(net "P5V_HDD35")
		)
		(pad "2" smd rect
			(at 0 1.397 270)
			(size 1.651 1.27)
			(layers "F.Cu" "F.Mask" "F.Paste")
			(net "GND")
		)
	)
	(footprint ""
		(layer "F.Cu")
		(at 321.634612 -129.66065 -90)
		(property "Reference" "C263"
			(at 0 0 270)
			(layer "F.SilkS")
			(hide yes)
			(effects
				(font
					(size 1.27 1.27)
				)
			)
		)
		(property "Value" "SCD01U16V1KX-GP"
			(at -2.8321 -1.7399 270)
			(unlocked yes)
			(layer "F.Fab")
			(hide yes)
			(effects
				(font
					(size 1.016 1.016)
					(thickness 0.1524)
				)
			)
		)
		(property "Device Type" "C0201H13"
			(at -2.8321 -3.2639 270)
			(unlocked yes)
			(layer "F.Fab")
			(hide yes)
			(effects
				(font
					(size 1.016 1.016)
					(thickness 0.1524)
				)
			)
		)
		(duplicate_pad_numbers_are_jumpers no)
		(fp_rect
			(start -0.2794 0.6477)
			(end 0.2794 -0.6477)
			(stroke
				(width 0)
				(type default)
			)
			(fill no)
			(layer "F.CrtYd")
		)
		(fp_rect
			(start -0.2794 0.6477)
			(end 0.2794 -0.6477)
			(stroke
				(width 0)
				(type default)
			)
			(fill no)
			(layer "F.Fab")
		)
		(pad "1" smd custom
			(at 0 -0.2794 270)
			(size 0.0762 0.0762)
			(layers "F.Cu" "F.Mask" "F.Paste")
			(net "SAS_HDD_RX_P18")
			(options
				(clearance outline)
				(anchor circle)
			)
			(primitives
				(gr_poly
					(pts
						(arc
							(start 0.1524 -0.127)
							(mid 0.137521 -0.162921)
							(end 0.1016 -0.1778)
						)
						(arc
							(start -0.1016 -0.1778)
							(mid -0.137521 -0.162921)
							(end -0.1524 -0.127)
						)
						(arc
							(start -0.1524 0.127)
							(mid -0.137521 0.162921)
							(end -0.1016 0.1778)
						)
						(arc
							(start 0.1016 0.1778)
							(mid 0.137521 0.162921)
							(end 0.1524 0.127)
						)
					)
					(width 0)
					(fill yes)
				)
			)
		)
		(pad "2" smd custom
			(at 0 0.2794 270)
			(size 0.0762 0.0762)
			(layers "F.Cu" "F.Mask" "F.Paste")
			(net "PHY_SCC_B_TO_DRV_B_18_DP")
			(options
				(clearance outline)
				(anchor circle)
			)
			(primitives
				(gr_poly
					(pts
						(arc
							(start 0.1524 -0.127)
							(mid 0.137521 -0.162921)
							(end 0.1016 -0.1778)
						)
						(arc
							(start -0.1016 -0.1778)
							(mid -0.137521 -0.162921)
							(end -0.1524 -0.127)
						)
						(arc
							(start -0.1524 0.127)
							(mid -0.137521 0.162921)
							(end -0.1016 0.1778)
						)
						(arc
							(start 0.1016 0.1778)
							(mid 0.137521 0.162921)
							(end 0.1524 0.127)
						)
					)
					(width 0)
					(fill yes)
				)
			)
		)
	)
	(footprint ""
		(layer "F.Cu")
		(at 465.943696 -214.860378 90)
		(property "Reference" "Q254"
			(at 0 0 90)
			(layer "F.SilkS")
			(hide yes)
			(effects
				(font
					(size 1.27 1.27)
				)
			)
		)
		(property "Value" "SSM3K324R-GP"
			(at 0.127 -8.9662 90)
			(unlocked yes)
			(layer "F.Fab")
			(hide yes)
			(effects
				(font
					(size 1.016 1.016)
					(thickness 0.1524)
				)
			)
		)
		(property "Device Type" "SOT23DGS2D4H35"
			(at 0.127 -10.4902 90)
			(unlocked yes)
			(layer "F.Fab")
			(hide yes)
			(effects
				(font
					(size 1.016 1.016)
					(thickness 0.1524)
				)
			)
		)
		(duplicate_pad_numbers_are_jumpers no)
		(fp_line
			(start 1.651 -1.778)
			(end -1.651 -1.778)
			(stroke
				(width 0.1524)
				(type default)
			)
			(layer "F.SilkS")
		)
		(fp_line
			(start -1.651 -1.778)
			(end -1.651 1.778)
			(stroke
				(width 0.1524)
				(type default)
			)
			(layer "F.SilkS")
		)
		(fp_line
			(start 1.651 1.778)
			(end 1.651 -1.778)
			(stroke
				(width 0.1524)
				(type default)
			)
			(layer "F.SilkS")
		)
		(fp_line
			(start -1.651 1.778)
			(end 1.651 1.778)
			(stroke
				(width 0.1524)
				(type default)
			)
			(layer "F.SilkS")
		)
		(fp_poly
			(pts
				(xy -1.778 1.8796) (xy -1.778 -1.8796) (xy 1.778 -1.8796) (xy 1.778 1.8796)
			)
			(stroke
				(width 0)
				(type default)
			)
			(fill no)
			(layer "F.CrtYd")
		)
		(fp_poly
			(pts
				(xy -1.778 1.8796) (xy -1.778 -1.8796) (xy 1.778 -1.8796) (xy 1.778 1.8796)
			)
			(stroke
				(width 0)
				(type default)
			)
			(fill no)
			(layer "F.Fab")
		)
		(pad "D" smd custom
			(at 0 -0.9525 90)
			(size 0.1905 0.1905)
			(layers "F.Cu" "F.Mask" "F.Paste")
			(net "DRV_ACT_11_N")
			(options
				(clearance outline)
				(anchor circle)
			)
			(primitives
				(gr_poly
					(pts
						(arc
							(start -0.1778 0.5715)
							(mid -0.321484 0.511984)
							(end -0.381 0.3683)
						)
						(arc
							(start -0.381 -0.3683)
							(mid -0.321484 -0.511984)
							(end -0.1778 -0.5715)
						)
						(arc
							(start 0.1778 -0.5715)
							(mid 0.321484 -0.511984)
							(end 0.381 -0.3683)
						)
						(arc
							(start 0.381 0.3683)
							(mid 0.321484 0.511984)
							(end 0.1778 0.5715)
						)
					)
					(width 0)
					(fill yes)
				)
			)
		)
		(pad "G" smd custom
			(at -0.98425 0.9525 90)
			(size 0.1905 0.1905)
			(layers "F.Cu" "F.Mask" "F.Paste")
			(net "DRIVE_B_11_ACT")
			(options
				(clearance outline)
				(anchor circle)
			)
			(primitives
				(gr_poly
					(pts
						(arc
							(start -0.1778 0.5715)
							(mid -0.321484 0.511984)
							(end -0.381 0.3683)
						)
						(arc
							(start -0.381 -0.3683)
							(mid -0.321484 -0.511984)
							(end -0.1778 -0.5715)
						)
						(arc
							(start 0.1778 -0.5715)
							(mid 0.321484 -0.511984)
							(end 0.381 -0.3683)
						)
						(arc
							(start 0.381 0.3683)
							(mid 0.321484 0.511984)
							(end 0.1778 0.5715)
						)
					)
					(width 0)
					(fill yes)
				)
			)
		)
		(pad "S" smd custom
			(at 0.98425 0.9525 90)
			(size 0.1905 0.1905)
			(layers "F.Cu" "F.Mask" "F.Paste")
			(net "GND")
			(options
				(clearance outline)
				(anchor circle)
			)
			(primitives
				(gr_poly
					(pts
						(arc
							(start -0.1778 0.5715)
							(mid -0.321484 0.511984)
							(end -0.381 0.3683)
						)
						(arc
							(start -0.381 -0.3683)
							(mid -0.321484 -0.511984)
							(end -0.1778 -0.5715)
						)
						(arc
							(start 0.1778 -0.5715)
							(mid 0.321484 -0.511984)
							(end 0.381 -0.3683)
						)
						(arc
							(start 0.381 0.3683)
							(mid 0.321484 0.511984)
							(end 0.1778 0.5715)
						)
					)
					(width 0)
					(fill yes)
				)
			)
		)
	)
	(footprint ""
		(layer "F.Cu")
		(at 392.938 -37.846 180)
		(property "Reference" "C446"
			(at 0 0 180)
			(layer "F.SilkS")
			(hide yes)
			(effects
				(font
					(size 1.27 1.27)
				)
			)
		)
		(property "Value" "SC1U16V3KX-5GP"
			(at 0 -2.8194 180)
			(unlocked yes)
			(layer "F.Fab")
			(hide yes)
			(effects
				(font
					(size 1.016 1.016)
					(thickness 0.1524)
				)
			)
		)
		(property "Device Type" "C603H36"
			(at 0 -4.3434 180)
			(unlocked yes)
			(layer "F.Fab")
			(hide yes)
			(effects
				(font
					(size 1.016 1.016)
					(thickness 0.1524)
				)
			)
		)
		(duplicate_pad_numbers_are_jumpers no)
		(fp_line
			(start 0.508 0)
			(end -0.508 0)
			(stroke
				(width 0.2032)
				(type default)
			)
			(layer "F.SilkS")
		)
		(fp_rect
			(start -0.5842 1.3335)
			(end 0.5842 -1.3335)
			(stroke
				(width 0)
				(type default)
			)
			(fill no)
			(layer "F.CrtYd")
		)
		(fp_rect
			(start -0.5842 1.3335)
			(end 0.5842 -1.3335)
			(stroke
				(width 0)
				(type default)
			)
			(fill no)
			(layer "F.Fab")
		)
		(pad "1" smd custom
			(at 0 -0.762 180)
			(size 0.2159 0.2159)
			(layers "F.Cu" "F.Mask" "F.Paste")
			(net "P5V_HDD32")
			(options
				(clearance outline)
				(anchor circle)
			)
			(primitives
				(gr_poly
					(pts
						(arc
							(start -0.3302 -0.4318)
							(mid -0.402042 -0.402042)
							(end -0.4318 -0.3302)
						)
						(arc
							(start -0.4318 0.3302)
							(mid -0.402042 0.402042)
							(end -0.3302 0.4318)
						)
						(arc
							(start 0.3302 0.4318)
							(mid 0.402042 0.402042)
							(end 0.4318 0.3302)
						)
						(arc
							(start 0.4318 -0.3302)
							(mid 0.402042 -0.402042)
							(end 0.3302 -0.4318)
						)
					)
					(width 0)
					(fill yes)
				)
			)
		)
		(pad "2" smd custom
			(at 0 0.762 180)
			(size 0.2159 0.2159)
			(layers "F.Cu" "F.Mask" "F.Paste")
			(net "GND")
			(options
				(clearance outline)
				(anchor circle)
			)
			(primitives
				(gr_poly
					(pts
						(arc
							(start -0.3302 -0.4318)
							(mid -0.402042 -0.402042)
							(end -0.4318 -0.3302)
						)
						(arc
							(start -0.4318 0.3302)
							(mid -0.402042 0.402042)
							(end -0.3302 0.4318)
						)
						(arc
							(start 0.3302 0.4318)
							(mid 0.402042 0.402042)
							(end 0.4318 0.3302)
						)
						(arc
							(start 0.4318 -0.3302)
							(mid 0.402042 -0.402042)
							(end 0.3302 -0.4318)
						)
					)
					(width 0)
					(fill yes)
				)
			)
		)
	)
	(footprint ""
		(layer "F.Cu")
		(at 244.199918 -175.79975)
		(property "Reference" ""
			(at 0 0 0)
			(layer "F.SilkS")
			(hide yes)
			(effects
				(font
					(size 1.27 1.27)
				)
			)
		)
		(property "Value" "*"
			(at -8.398764 -8.057642 0)
			(unlocked yes)
			(layer "F.Fab")
			(hide yes)
			(effects
				(font
					(size 1.016 1.016)
					(thickness 0.1524)
				)
			)
		)
		(duplicate_pad_numbers_are_jumpers no)
		(fp_poly
			(pts
				(arc
					(start 7.3152 0)
					(mid 0 7.3152)
					(end -7.3152 0)
				)
				(arc
					(start -7.3152 -5.9944)
					(mid 0 -13.3096)
					(end 7.3152 -5.9944)
				)
			)
			(stroke
				(width 0)
				(type default)
			)
			(fill no)
			(layer "B.CrtYd")
		)
		(fp_poly
			(pts
				(arc
					(start 7.3152 0)
					(mid 0 7.3152)
					(end -7.3152 0)
				)
				(arc
					(start -7.3152 -5.9944)
					(mid 0 -13.3096)
					(end 7.3152 -5.9944)
				)
			)
			(stroke
				(width 0)
				(type default)
			)
			(fill no)
			(layer "F.CrtYd")
		)
		(fp_poly
			(pts
				(arc
					(start 7.3152 0)
					(mid 0 7.3152)
					(end -7.3152 0)
				)
				(arc
					(start -7.3152 -5.9944)
					(mid 0 -13.3096)
					(end 7.3152 -5.9944)
				)
			)
			(stroke
				(width 0)
				(type default)
			)
			(fill no)
			(layer "B.Fab")
		)
		(fp_poly
			(pts
				(arc
					(start 7.3152 0)
					(mid 0 7.3152)
					(end -7.3152 0)
				)
				(arc
					(start -7.3152 -5.9944)
					(mid 0 -13.3096)
					(end 7.3152 -5.9944)
				)
			)
			(stroke
				(width 0)
				(type default)
			)
			(fill no)
			(layer "F.Fab")
		)
		(pad "1" thru_hole oval
			(at 0 0)
			(size 14.0208 20.0152)
			(drill 0.0254
				(offset 0 -2.9972)
			)
			(layers "*.Cu" "*.Mask")
			(remove_unused_layers no)
			(net "Net_18")
			(clearance -1.002284)
			(thermal_gap 0.1524)
			(padstack
				(mode front_inner_back)
				(layer "Inner"
					(shape custom)
					(size 2.928012 2.928012)
					(options
						(anchor circle)
					)
					(primitives
						(gr_poly
							(pts
								(arc
									(start 4.571746 -2.084324)
									(mid 0.000333 7.430372)
									(end -4.571492 -2.084324)
								)
								(arc
									(start -4.571492 -2.084324)
									(mid -3.570296 -3.611977)
									(end -2.875026 -5.30098)
								)
								(arc
									(start -2.875026 -5.30098)
									(mid 0.000217 -7.43089)
									(end 2.87528 -5.30098)
								)
								(arc
									(start 2.87528 -5.30098)
									(mid 3.570511 -3.611956)
									(end 4.571746 -2.084324)
								)
							)
							(width 0)
							(fill yes)
						)
					)
					(clearance 0.1524)
				)
				(layer "B.Cu"
					(shape oval)
					(size 14.0208 20.0152)
					(offset 0 -2.9972)
					(clearance -1.002284)
				)
			)
		)
		(zone
			(layers "F.Cu" "B.Cu" "In1.Cu" "In2.Cu" "In3.Cu" "In4.Cu" "In5.Cu" "In6.Cu")
			(hatch none 0.5)
			(connect_pads
				(clearance 0)
			)
			(min_thickness 0.25)
			(keepout
				(tracks not_allowed)
				(vias allowed)
				(pads allowed)
				(copperpour not_allowed)
				(footprints allowed)
			)
			(placement
				(enabled no)
				(sheetname "")
			)
			(fill
				(thermal_gap 0.5)
				(thermal_bridge_width 0.5)
				(island_removal_mode 0)
			)
			(polygon
				(pts
					(arc
						(start 237.189518 -181.79415)
						(mid 244.199918 -188.80455)
						(end 251.210318 -181.79415)
					)
					(arc
						(start 251.210318 -175.79975)
						(mid 244.199918 -168.78935)
						(end 237.189518 -175.79975)
					)
				)
			)
		)
	)
	(footprint ""
		(layer "F.Cu")
		(at 265.625072 -351.431606 90)
		(property "Reference" "R1052"
			(at 0 0 90)
			(layer "F.SilkS")
			(hide yes)
			(effects
				(font
					(size 1.27 1.27)
				)
			)
		)
		(property "Value" "10R5F-1-GP"
			(at 0 -8.9535 90)
			(unlocked yes)
			(layer "F.Fab")
			(hide yes)
			(effects
				(font
					(size 1.27 1.016)
					(thickness 0.1524)
				)
			)
		)
		(property "Device Type" "R805H24"
			(at 0 -10.6299 90)
			(unlocked yes)
			(layer "F.Fab")
			(hide yes)
			(effects
				(font
					(size 1.27 1.016)
					(thickness 0.1524)
				)
			)
		)
		(duplicate_pad_numbers_are_jumpers no)
		(fp_line
			(start 0.889 -1.7018)
			(end -0.889 -1.7018)
			(stroke
				(width 0.1524)
				(type default)
			)
			(layer "F.SilkS")
		)
		(fp_line
			(start 0.889 -1.7018)
			(end 0.889 -0.381)
			(stroke
				(width 0.1524)
				(type default)
			)
			(layer "F.SilkS")
		)
		(fp_line
			(start -0.889 -1.7018)
			(end -0.889 0.2794)
			(stroke
				(width 0.1524)
				(type default)
			)
			(layer "F.SilkS")
		)
		(fp_line
			(start -0.889 0.0762)
			(end -0.889 1.7018)
			(stroke
				(width 0.1524)
				(type default)
			)
			(layer "F.SilkS")
		)
		(fp_line
			(start 0.889 1.7018)
			(end 0.889 -0.508)
			(stroke
				(width 0.1524)
				(type default)
			)
			(layer "F.SilkS")
		)
		(fp_line
			(start -0.889 1.7018)
			(end 0.889 1.7018)
			(stroke
				(width 0.1524)
				(type default)
			)
			(layer "F.SilkS")
		)
		(fp_poly
			(pts
				(xy 0.9652 -1.778) (xy 0.9652 1.778) (xy -0.9652 1.778) (xy -0.9652 -1.778)
			)
			(stroke
				(width 0)
				(type default)
			)
			(fill no)
			(layer "F.CrtYd")
		)
		(fp_rect
			(start -0.9652 1.778)
			(end 0.9652 -1.778)
			(stroke
				(width 0)
				(type default)
			)
			(fill no)
			(layer "F.Fab")
		)
		(pad "1" smd rect
			(at 0 -0.9652 90)
			(size 1.397 1.143)
			(layers "F.Cu" "F.Mask" "F.Paste")
			(net "MB3_12V_CTRL_GATE1")
		)
		(pad "2" smd rect
			(at 0 0.9652 90)
			(size 1.397 1.143)
			(layers "F.Cu" "F.Mask" "F.Paste")
			(net "MB3_CM_GATE_R")
		)
	)
)
